# T6G (Grand Teton) — schematic netlist excerpt (pin names and nets, part order shuffled) for the footprints in the layout excerpt that follows; sources: Cadence DE-HDL packaged netlist, KiCad conversion of 04192023_DAF0TMB3IC0_F0TG_MB_C_brd_V02_OCP.brd

R3976  Q_RES  100K 1% CHIP  pkg 0402LF  page 146 : A = P3V3_AUX ; B = P12V_E1S_FAULT_0
R6073  Q_RES  0 5% CHIP  pkg 0402LF  page 82 : A = FM_PDB_BUF_EN_R_N ; B = FM_PDB_BUF_EN_N
PC6905  Q_CAP  22UF 16V 20% X6S  pkg C0805  page 361 : A = SW_P12V_AUX_P1V8_RETIMER_CPU1_FLT ; B = GND

(kicad_pcb
	(version 20260206)
	(generator "pcbnew")
	(generator_version "10.0")
	(general
		(thickness 1.6)
		(legacy_teardrops no)
	)
	(paper "A4")
	(title_block
		(title "04192023_DAF0TMB3IC0_F0TG_MB_C_brd_V02_OCP.brd")
		(comment 1 "Grand Teton / footprints 617-619 of 8354")
	)
	(layers
		(0 "F.Cu" signal "TOP")
		(4 "In1.Cu" signal "GND")
		(6 "In2.Cu" signal "IN1")
		(8 "In3.Cu" signal "GND1")
		(10 "In4.Cu" signal "IN2")
		(12 "In5.Cu" signal "GND2")
		(14 "In6.Cu" signal "IN3")
		(16 "In7.Cu" signal "GND3")
		(18 "In8.Cu" signal "VCC")
		(20 "In9.Cu" signal "VCC1")
		(22 "In10.Cu" signal "GND4")
		(24 "In11.Cu" signal "IN4")
		(26 "In12.Cu" signal "GND5")
		(28 "In13.Cu" signal "IN5")
		(30 "In14.Cu" signal "GND6")
		(32 "In15.Cu" signal "IN6")
		(34 "In16.Cu" signal "GND7")
		(2 "B.Cu" signal "BOTTOM")
		(9 "F.Adhes" user "F.Adhesive")
		(11 "B.Adhes" user "B.Adhesive")
		(13 "F.Paste" user "Package Geometry/Pastemask Top")
		(15 "B.Paste" user "Package Geometry/Pastemask Bottom")
		(5 "F.SilkS" user "Ref Des/Silkscreen Top")
		(7 "B.SilkS" user "Ref Des/Silkscreen Bottom")
		(1 "F.Mask" user "Board Geometry/Soldermask Top")
		(3 "B.Mask" user "Board Geometry/Soldermask Bottom")
		(17 "Dwgs.User" user "User.Drawings")
		(19 "Cmts.User" user "User.Comments")
		(21 "Eco1.User" user "User.Eco1")
		(23 "Eco2.User" user "User.Eco2")
		(25 "Edge.Cuts" user "Board Geometry/Outline")
		(27 "Margin" user)
		(31 "F.CrtYd" user "Package Geometry/Place Bound Top")
		(29 "B.CrtYd" user "Package Geometry/Place Bound Bottom")
		(35 "F.Fab" user "Ref Des/Assembly Top")
		(33 "B.Fab" user "Ref Des/Assembly Bottom")
	)
	(footprint ""
		(layer "F.Cu")
		(at 254 -38.683946 180)
		(property "Reference" "R3976"
			(at 0 0 180)
			(layer "F.SilkS")
			(hide yes)
			(effects
				(font
					(size 1.27 1.27)
				)
			)
		)
		(property "Value" ""
			(at 0 0 180)
			(layer "F.Fab")
			(effects
				(font
					(size 1.27 1.27)
				)
			)
		)
		(duplicate_pad_numbers_are_jumpers no)
		(fp_line
			(start 0.7874 0.4064)
			(end -0.7874 0.4064)
			(stroke
				(width 0.1524)
				(type default)
			)
			(layer "F.SilkS")
		)
		(fp_line
			(start 0.7874 -0.4064)
			(end 0.7874 0.4064)
			(stroke
				(width 0.1524)
				(type default)
			)
			(layer "F.SilkS")
		)
		(fp_line
			(start -0.7874 0.4064)
			(end -0.7874 -0.4064)
			(stroke
				(width 0.1524)
				(type default)
			)
			(layer "F.SilkS")
		)
		(fp_line
			(start -0.7874 -0.4064)
			(end 0.7874 -0.4064)
			(stroke
				(width 0.1524)
				(type default)
			)
			(layer "F.SilkS")
		)
		(fp_line
			(start 0.67945 0.3048)
			(end 0.120396 0.3048)
			(stroke
				(width 0.1)
				(type default)
			)
			(layer "F.Fab")
		)
		(fp_line
			(start 0.67945 -0.3048)
			(end 0.67945 0.3048)
			(stroke
				(width 0.1)
				(type default)
			)
			(layer "F.Fab")
		)
		(fp_line
			(start 0.12065 -0.2794)
			(end 0.12065 -0.3048)
			(stroke
				(width 0.1)
				(type default)
			)
			(layer "F.Fab")
		)
		(fp_line
			(start 0.12065 -0.3048)
			(end 0.67945 -0.3048)
			(stroke
				(width 0.1)
				(type default)
			)
			(layer "F.Fab")
		)
		(fp_line
			(start 0.120396 0.3048)
			(end 0.120396 0.2794)
			(stroke
				(width 0.1)
				(type default)
			)
			(layer "F.Fab")
		)
		(fp_line
			(start 0.120396 0.2794)
			(end -0.12065 0.2794)
			(stroke
				(width 0.1)
				(type default)
			)
			(layer "F.Fab")
		)
		(fp_line
			(start -0.12065 0.3048)
			(end -0.67945 0.3048)
			(stroke
				(width 0.1)
				(type default)
			)
			(layer "F.Fab")
		)
		(fp_line
			(start -0.12065 0.2794)
			(end -0.12065 0.3048)
			(stroke
				(width 0.1)
				(type default)
			)
			(layer "F.Fab")
		)
		(fp_line
			(start -0.12065 -0.2794)
			(end 0.12065 -0.2794)
			(stroke
				(width 0.1)
				(type default)
			)
			(layer "F.Fab")
		)
		(fp_line
			(start -0.12065 -0.305054)
			(end -0.12065 -0.2794)
			(stroke
				(width 0.1)
				(type default)
			)
			(layer "F.Fab")
		)
		(fp_line
			(start -0.67945 0.3048)
			(end -0.67945 -0.305054)
			(stroke
				(width 0.1)
				(type default)
			)
			(layer "F.Fab")
		)
		(fp_line
			(start -0.67945 -0.305054)
			(end -0.12065 -0.305054)
			(stroke
				(width 0.1)
				(type default)
			)
			(layer "F.Fab")
		)
		(pad "1" smd circle
			(at -0.40005 0 180)
			(size 0 0)
			(layers "F.Cu" "F.Mask" "F.Paste")
			(net "P3V3_AUX")
		)
		(pad "2" smd circle
			(at 0.40005 0 180)
			(size 0 0)
			(layers "F.Cu" "F.Mask" "F.Paste")
			(net "P12V_E1S_FAULT_0")
		)
	)
	(footprint ""
		(layer "F.Cu")
		(at 189.865 -96.103948 90)
		(property "Reference" "R6073"
			(at 0 0 90)
			(layer "F.SilkS")
			(hide yes)
			(effects
				(font
					(size 1.27 1.27)
				)
			)
		)
		(property "Value" ""
			(at 0 0 90)
			(layer "F.Fab")
			(effects
				(font
					(size 1.27 1.27)
				)
			)
		)
		(duplicate_pad_numbers_are_jumpers no)
		(fp_line
			(start 0.7874 -0.4064)
			(end 0.7874 0.4064)
			(stroke
				(width 0.1524)
				(type default)
			)
			(layer "F.SilkS")
		)
		(fp_line
			(start -0.7874 -0.4064)
			(end 0.7874 -0.4064)
			(stroke
				(width 0.1524)
				(type default)
			)
			(layer "F.SilkS")
		)
		(fp_line
			(start 0.7874 0.4064)
			(end -0.7874 0.4064)
			(stroke
				(width 0.1524)
				(type default)
			)
			(layer "F.SilkS")
		)
		(fp_line
			(start -0.7874 0.4064)
			(end -0.7874 -0.4064)
			(stroke
				(width 0.1524)
				(type default)
			)
			(layer "F.SilkS")
		)
		(fp_line
			(start -0.12065 -0.305054)
			(end -0.12065 -0.2794)
			(stroke
				(width 0.1)
				(type default)
			)
			(layer "F.Fab")
		)
		(fp_line
			(start -0.67945 -0.305054)
			(end -0.12065 -0.305054)
			(stroke
				(width 0.1)
				(type default)
			)
			(layer "F.Fab")
		)
		(fp_line
			(start 0.67945 -0.3048)
			(end 0.67945 0.3048)
			(stroke
				(width 0.1)
				(type default)
			)
			(layer "F.Fab")
		)
		(fp_line
			(start 0.12065 -0.3048)
			(end 0.67945 -0.3048)
			(stroke
				(width 0.1)
				(type default)
			)
			(layer "F.Fab")
		)
		(fp_line
			(start 0.12065 -0.2794)
			(end 0.12065 -0.3048)
			(stroke
				(width 0.1)
				(type default)
			)
			(layer "F.Fab")
		)
		(fp_line
			(start -0.12065 -0.2794)
			(end 0.12065 -0.2794)
			(stroke
				(width 0.1)
				(type default)
			)
			(layer "F.Fab")
		)
		(fp_line
			(start 0.120396 0.2794)
			(end -0.12065 0.2794)
			(stroke
				(width 0.1)
				(type default)
			)
			(layer "F.Fab")
		)
		(fp_line
			(start -0.12065 0.2794)
			(end -0.12065 0.3048)
			(stroke
				(width 0.1)
				(type default)
			)
			(layer "F.Fab")
		)
		(fp_line
			(start 0.67945 0.3048)
			(end 0.120396 0.3048)
			(stroke
				(width 0.1)
				(type default)
			)
			(layer "F.Fab")
		)
		(fp_line
			(start 0.120396 0.3048)
			(end 0.120396 0.2794)
			(stroke
				(width 0.1)
				(type default)
			)
			(layer "F.Fab")
		)
		(fp_line
			(start -0.12065 0.3048)
			(end -0.67945 0.3048)
			(stroke
				(width 0.1)
				(type default)
			)
			(layer "F.Fab")
		)
		(fp_line
			(start -0.67945 0.3048)
			(end -0.67945 -0.305054)
			(stroke
				(width 0.1)
				(type default)
			)
			(layer "F.Fab")
		)
		(pad "1" smd circle
			(at -0.40005 0 90)
			(size 0 0)
			(layers "F.Cu" "F.Mask" "F.Paste")
			(net "FM_PDB_BUF_EN_R_N")
		)
		(pad "2" smd circle
			(at 0.40005 0 90)
			(size 0 0)
			(layers "F.Cu" "F.Mask" "F.Paste")
			(net "FM_PDB_BUF_EN_N")
		)
	)
	(footprint ""
		(layer "F.Cu")
		(at 233.2228 -287.0708)
		(property "Reference" "PC6905"
			(at 0 0 0)
			(layer "F.SilkS")
			(hide yes)
			(effects
				(font
					(size 1.27 1.27)
				)
			)
		)
		(property "Value" ""
			(at 0 0 0)
			(layer "F.Fab")
			(effects
				(font
					(size 1.27 1.27)
				)
			)
		)
		(duplicate_pad_numbers_are_jumpers no)
		(fp_line
			(start -1.524 -0.762)
			(end 1.524 -0.762)
			(stroke
				(width 0.1524)
				(type default)
			)
			(layer "F.SilkS")
		)
		(fp_line
			(start -1.524 0.762)
			(end -1.524 -0.762)
			(stroke
				(width 0.1524)
				(type default)
			)
			(layer "F.SilkS")
		)
		(fp_line
			(start 1.524 -0.762)
			(end 1.524 0.762)
			(stroke
				(width 0.1524)
				(type default)
			)
			(layer "F.SilkS")
		)
		(fp_line
			(start 1.524 0.762)
			(end -1.524 0.762)
			(stroke
				(width 0.1524)
				(type default)
			)
			(layer "F.SilkS")
		)
		(fp_line
			(start -1.1049 -0.724916)
			(end -1.1049 0.724916)
			(stroke
				(width 0.1)
				(type default)
			)
			(layer "F.Fab")
		)
		(fp_line
			(start -1.1049 0.724916)
			(end 1.1049 0.724916)
			(stroke
				(width 0.1)
				(type default)
			)
			(layer "F.Fab")
		)
		(fp_line
			(start 1.1049 -0.724916)
			(end -1.1049 -0.724916)
			(stroke
				(width 0.1)
				(type default)
			)
			(layer "F.Fab")
		)
		(fp_line
			(start 1.1049 0.724916)
			(end 1.1049 -0.724916)
			(stroke
				(width 0.1)
				(type default)
			)
			(layer "F.Fab")
		)
		(pad "1" smd rect
			(at -0.889 0 180)
			(size 1.016 1.27)
			(layers "F.Cu" "F.Mask" "F.Paste")
			(net "SW_P12V_AUX_P1V8_RETIMER_CPU1_FLT")
		)
		(pad "2" smd rect
			(at 0.889 0 180)
			(size 1.016 1.27)
			(layers "F.Cu" "F.Mask" "F.Paste")
			(net "GND")
		)
	)
)
